;LEADER: 12 
;HEADER: 
;CODE  : ASCII 
;FILE  : 9127_F0T_Expander_BD_F_v02_0110_1240-bd-18-15.drl for backdrilling ... from layer BOTTOM to layer GND6
;DESIGN: 9127_F0T_Expander_BD_F_v02_0110_1240.brd
;MUST-NOT-CUT-LAYER = IN5,  MAX_DRILL_DEPTH = 25.85 MILS,  MFG_STUB_LENGTH = 0.00 MILS
;   BackdrillSize 1. = 15.700000 Tolerance = +0.000000/-0.000000 NON_PLATED MILS Quantity = 136
;   BackdrillSize 2. = 17.700000 Tolerance = +0.000000/-0.000000 NON_PLATED MILS Quantity = 260
;   BackdrillSize 3. = 19.900000 Tolerance = +0.000000/-0.000000 NON_PLATED MILS Quantity = 132
%
G90
X0154429Y1133169
X0161909Y1133169
X0165649Y1133169
X0143208Y1136909
X0146948Y1136909
X0150689Y1133169
X0169389Y1136909
X0173129Y1136909
X0189960Y1232283
X0227362Y1236023
X0193700Y1224803
X0204921Y1236023
X0216141Y1228543
X0201181Y1228543
X0223622Y1228543
X0208661Y1224803
X0227362Y1232283
X0174999Y1236023
X0186220Y1228543
X0223622Y1224803
X0216141Y1224803
X0212401Y1236023
X0189960Y1236023
X0178740Y1224803
X0197440Y1232283
X0171259Y1228543
X0219881Y1236023
X0193700Y1228543
X0208661Y1228543
X0174999Y1232283
X0212401Y1232283
X0182480Y1232283
X0201181Y1224803
X0219881Y1232283
X0186220Y1224803
X0204921Y1232283
X0197440Y1236023
X0182480Y1236023
X0171259Y1224803
X0178740Y1228543
X0654527Y1232283
X0635827Y1224803
X0650787Y1224803
X0632086Y1236023
X0632086Y1232283
X0635827Y1228543
X0650787Y1228543
X0643307Y1228543
X0647047Y1232283
X0643307Y1224803
X0628346Y1228543
X0628346Y1224803
X0639567Y1232283
X0654527Y1236023
X0647047Y1236023
X0639567Y1236023
X0729331Y1232283
X0729331Y1236023
X0718110Y1224803
X0740551Y1228543
X0740551Y1224803
X0736811Y1236023
X0744291Y1232283
X0725590Y1224803
X0721850Y1232283
X0733071Y1224803
X0721850Y1236023
X0736811Y1232283
X0733071Y1228543
X0744291Y1236023
X0725590Y1228543
X0718110Y1228543
X1130314Y1224803
X1085432Y1228543
X1141535Y1232283
X1085432Y1224803
X1122834Y1228543
X1111613Y1236023
X1092913Y1228543
X1130314Y1228543
X1096653Y1232283
X1137795Y1224803
X1107873Y1228543
X1126574Y1236023
X1115354Y1224803
X1119094Y1236023
X1111613Y1232283
X1100393Y1224803
X1115354Y1228543
X1096653Y1236023
X1089172Y1236023
X1107873Y1224803
X1126574Y1232283
X1104133Y1232283
X1141535Y1236023
X1092913Y1224803
X1104133Y1236023
X1134054Y1232283
X1137795Y1228543
X1134054Y1236023
X1089172Y1232283
X1100393Y1228543
X1119094Y1232283
X1122834Y1224803
X1568700Y1232283
X1564960Y1228543
X1557480Y1224803
X1542519Y1224803
X1561220Y1232283
X1561220Y1236023
X1557480Y1228543
X1546259Y1236023
X1550000Y1224803
X1542519Y1228543
X1553740Y1236023
X1550000Y1228543
X1564960Y1224803
X1553740Y1232283
X1568700Y1236023
X1546259Y1232283
X1639763Y1228543
X1650984Y1232283
X1647244Y1224803
X1650984Y1236023
X1636023Y1232283
X1643504Y1236023
X1632283Y1224803
X1658464Y1236023
X1654724Y1224803
X1643504Y1232283
X1636023Y1236023
X1658464Y1232283
X1639763Y1224803
X1647244Y1228543
X1654724Y1228543
X1632283Y1228543
M00
X0257263Y1384297
X0241623Y1360099
X0253863Y1384297
X0266103Y1408495
X0245023Y1360099
X0266103Y1360099
X0257263Y1372385
X0266103Y1348187
X0245023Y1348187
X0253863Y1372385
X0266103Y1396583
X0241623Y1348187
X0227249Y1461853
X0227249Y1458453
X0227249Y1450853
X0227249Y1447453
X0278343Y1384297
X0281743Y1384297
X0290583Y1360099
X0293983Y1360099
X0290583Y1408495
X0293983Y1408495
X0302823Y1384297
X0306223Y1384297
X0367423Y1408495
X0364023Y1408495
X0315063Y1408495
X0318463Y1360099
X0351783Y1384297
X0339543Y1408495
X0339543Y1360099
X0315063Y1360099
X0355183Y1384297
X0330703Y1384297
X0318463Y1408495
X0327303Y1384297
X0342943Y1360099
X0269503Y1360099
X0364023Y1360099
X0269503Y1408495
X0342943Y1408495
X0367423Y1360099
X0290583Y1348187
X0367423Y1396583
X0290583Y1396583
X0318463Y1396583
X0342943Y1396583
X0318463Y1348187
X0367423Y1348187
X0327303Y1372385
X0364023Y1396583
X0281743Y1372385
X0364023Y1348187
X0339543Y1396583
X0342943Y1348187
X0293983Y1348187
X0302823Y1372385
X0355183Y1372385
X0293983Y1396583
X0330703Y1372385
X0339543Y1348187
X0315063Y1348187
X0351783Y1372385
X0278343Y1372385
X0315063Y1396583
X0306223Y1372385
X0269503Y1396583
X0269503Y1348187
X0443802Y1360099
X0464882Y1360099
X0468282Y1408495
X0456042Y1384297
X0468282Y1360099
X0464882Y1408495
X0440402Y1360099
X0452642Y1384297
X0464882Y1348187
X0456042Y1372385
X0452642Y1372385
X0468282Y1348187
X0443802Y1348187
X0440402Y1348187
X0464882Y1396583
X0468282Y1396583
X0477122Y1384297
X0480522Y1384297
X0489362Y1360099
X0492762Y1360099
X0489362Y1408495
X0492762Y1408495
X0501602Y1384297
X0505002Y1384297
X0538322Y1348187
X0541722Y1348187
X0513842Y1348187
X0566202Y1348187
X0562802Y1348187
X0538322Y1360099
X0553962Y1372385
X0562802Y1396583
X0526082Y1384297
X0513842Y1408495
X0526082Y1372385
X0517242Y1408495
X0538322Y1408495
X0513842Y1396583
X0541722Y1408495
X0501602Y1372385
X0538322Y1396583
X0517242Y1396583
X0541722Y1360099
X0562802Y1360099
X0566202Y1360099
X0517242Y1360099
X0529482Y1384297
X0489362Y1396583
X0562802Y1408495
X0550562Y1384297
X0492762Y1396583
X0480522Y1372385
X0553962Y1384297
X0489362Y1348187
X0513842Y1360099
X0477122Y1372385
X0566202Y1408495
X0505002Y1372385
X0492762Y1348187
X0550562Y1372385
X0541722Y1396583
X0566202Y1396583
X0529482Y1372385
X0517242Y1348187
X1254806Y1408495
X1267046Y1384297
X1233726Y1360099
X1258206Y1360099
X1245966Y1384297
X1254806Y1360099
X1258206Y1408495
X1230326Y1360099
X1242566Y1384297
X1233726Y1348187
X1230326Y1348187
X1258206Y1348187
X1254806Y1396583
X1267046Y1372385
X1258206Y1396583
X1245966Y1372385
X1254806Y1348187
X1242566Y1372385
X1294926Y1384297
X1343886Y1384297
X1331646Y1360099
X1340486Y1384297
X1303766Y1408495
X1282686Y1408495
X1352726Y1360099
X1307166Y1408495
X1328246Y1408495
X1282686Y1360099
X1328246Y1360099
X1291526Y1384297
X1356126Y1408495
X1279286Y1360099
X1303766Y1360099
X1319406Y1384297
X1279286Y1408495
X1316006Y1384297
X1352726Y1408495
X1270446Y1384297
X1356126Y1360099
X1307166Y1360099
X1331646Y1408495
X1328246Y1396583
X1352726Y1396583
X1319406Y1372385
X1294926Y1372385
X1331646Y1396583
X1352726Y1348187
X1282686Y1396583
X1331646Y1348187
X1303766Y1348187
X1307166Y1396583
X1291526Y1372385
X1307166Y1348187
X1279286Y1396583
X1328246Y1348187
X1279286Y1348187
X1356126Y1396583
X1282686Y1348187
X1340486Y1372385
X1356126Y1348187
X1343886Y1372385
X1270446Y1372385
X1303766Y1396583
X1316006Y1372385
X1461370Y1360099
X1464770Y1360099
X1461370Y1348187
X1464770Y1348187
X1534810Y1360099
X1562690Y1408495
X1550450Y1384297
X1534810Y1408495
X1562690Y1360099
X1559290Y1408495
X1538210Y1360099
X1559290Y1360099
X1547050Y1384297
X1538210Y1408495
X1477010Y1384297
X1522570Y1384297
X1513730Y1408495
X1489250Y1360099
X1510330Y1408495
X1485850Y1360099
X1485850Y1408495
X1498090Y1384297
X1513730Y1360099
X1489250Y1408495
X1501490Y1384297
X1473610Y1384297
X1510330Y1360099
X1525970Y1384297
X1522570Y1372385
X1513730Y1396583
X1498090Y1372385
X1510330Y1348187
X1550450Y1372385
X1559290Y1396583
X1534810Y1396583
X1562690Y1348187
X1534810Y1348187
X1559290Y1348187
X1538210Y1396583
X1547050Y1372385
X1562690Y1396583
X1513730Y1348187
X1501490Y1372385
X1477010Y1372385
X1538210Y1348187
X1485850Y1348187
X1489250Y1396583
X1489250Y1348187
X1510330Y1396583
X1485850Y1396583
X1525970Y1372385
X1473610Y1372385
X1574930Y1384297
X1583770Y1360099
X1587170Y1408495
X1571530Y1384297
X1583770Y1408495
X1587170Y1360099
X1571530Y1372385
X1574930Y1372385
X1587170Y1396583
X1583770Y1348187
X1583770Y1396583
X1587170Y1348187
M00
X0187835Y1483426
X0187835Y1478308
X0179173Y1479095
X0179173Y1473977
X0291771Y1616496
X0283110Y1612166
X0291771Y1611378
X0283110Y1607048
X0309094Y1616496
X0300433Y1612166
X0309094Y1611378
X0300433Y1607048
X0326417Y1616496
X0317756Y1612166
X0326417Y1611378
X0317756Y1607048
X0343740Y1616496
X0335078Y1612166
X0343740Y1611378
X0335078Y1607048
X0291771Y1514134
X0283110Y1509804
X0291771Y1509016
X0283110Y1504685
X0309094Y1514134
X0300433Y1509804
X0309094Y1509016
X0300433Y1504685
X0326417Y1514134
X0317756Y1509804
X0326417Y1509016
X0317756Y1504685
X0343740Y1514134
X0335078Y1509804
X0343740Y1509016
X0335078Y1504685
X0465000Y1498780
X0456339Y1494449
X0465000Y1493662
X0456339Y1489331
X0465000Y1616496
X0456339Y1612166
X0465000Y1611378
X0456339Y1607048
X0482323Y1616496
X0473662Y1612166
X0482323Y1611378
X0473662Y1607048
X0499646Y1616496
X0490985Y1612166
X0499646Y1611378
X0490985Y1607048
X0516969Y1616496
X0508307Y1612166
X0516969Y1611378
X0508307Y1607048
X0482323Y1498780
X0473662Y1494449
X0482323Y1493662
X0473662Y1489331
X0499646Y1498780
X0490985Y1494449
X0499646Y1493662
X0490985Y1489331
X0516969Y1498780
X0508307Y1494449
X0516969Y1493662
X0508307Y1489331
X1313740Y1616496
X1305079Y1612166
X1313740Y1611378
X1305079Y1607048
X1331063Y1616496
X1322402Y1612166
X1331063Y1611378
X1322402Y1607048
X1348386Y1616496
X1339725Y1612166
X1348386Y1611378
X1339725Y1607048
X1365709Y1616496
X1357047Y1612166
X1365709Y1611378
X1357047Y1607048
X1313740Y1514134
X1305079Y1509804
X1313740Y1509016
X1305079Y1504685
X1331063Y1514134
X1322402Y1509804
X1331063Y1509016
X1322402Y1504685
X1348386Y1514134
X1339725Y1509804
X1348386Y1509016
X1339725Y1504685
X1365709Y1514134
X1357047Y1509804
X1365709Y1509016
X1357047Y1504685
X1486968Y1616496
X1478307Y1612166
X1486968Y1611378
X1478307Y1607048
X1504291Y1616496
X1495630Y1612166
X1504291Y1611378
X1495630Y1607048
X1521614Y1616496
X1512953Y1612166
X1521614Y1611378
X1512953Y1607048
X1538937Y1616496
X1530275Y1612166
X1538937Y1611378
X1530275Y1607048
X1486968Y1498780
X1478307Y1494449
X1486968Y1493662
X1478307Y1489331
X1504291Y1498780
X1495630Y1494449
X1504291Y1493662
X1495630Y1489331
X1521614Y1498780
X1512953Y1494449
X1521614Y1493662
X1512953Y1489331
X1538937Y1498780
X1530275Y1494449
X1538937Y1493662
X1530275Y1489331
M30
